(kicad_pcb
	(version 20260206)
	(generator "pcbnew")
	(generator_version "10.0")
	(general
		(thickness 1.6)
		(legacy_teardrops no)
	)
	(paper "A4")
	(title_block
		(title "netronome-mezz — pcbd0082-001_rev01_jul9_a.brd")
		(comment 1 "Open CloudServer (Microsoft) / footprints 421-430 of 714")
	)
	(layers
		(0 "F.Cu" signal "TOP")
		(4 "In1.Cu" signal "02_GND")
		(6 "In2.Cu" signal "03_SIG")
		(8 "In3.Cu" signal "04_SIG")
		(10 "In4.Cu" signal "05_GND")
		(12 "In5.Cu" signal "06_PWR1")
		(14 "In6.Cu" signal "07_SIG")
		(16 "In7.Cu" signal "08_SIG")
		(18 "In8.Cu" signal "09_GND")
		(2 "B.Cu" signal "BOTTOM")
		(9 "F.Adhes" user "F.Adhesive")
		(11 "B.Adhes" user "B.Adhesive")
		(13 "F.Paste" user "Package Geometry/Pastemask Top")
		(15 "B.Paste" user "Package Geometry/Pastemask Bottom")
		(5 "F.SilkS" user "Ref Des/Silkscreen Top")
		(7 "B.SilkS" user "Ref Des/Silkscreen Bottom")
		(1 "F.Mask" user "Board Geometry/Soldermask Top")
		(3 "B.Mask" user "Board Geometry/Soldermask Bottom")
		(17 "Dwgs.User" user "User.Drawings")
		(19 "Cmts.User" user "User.Comments")
		(21 "Eco1.User" user "User.Eco1")
		(23 "Eco2.User" user "User.Eco2")
		(25 "Edge.Cuts" user "Board Geometry/Outline")
		(27 "Margin" user)
		(31 "F.CrtYd" user "Package Geometry/Place Bound Top")
		(29 "B.CrtYd" user "Package Geometry/Place Bound Bottom")
		(35 "F.Fab" user "Ref Des/Assembly Top")
		(33 "B.Fab" user "Ref Des/Assembly Bottom")
		(45 "User.4" user "COMPVAL_TYPE_BOTTOM")
	)
	(footprint ""
		(layer "B.Cu")
		(at 22.352 13.589)
		(property "Reference" "R24"
			(at 0 0 0)
			(layer "B.SilkS")
			(hide yes)
			(effects
				(font
					(size 1.27 1.27)
				)
				(justify mirror)
			)
		)
		(property "Value" "4.75K"
			(at 0.148158 1.3462 270)
			(unlocked yes)
			(layer "B.Fab")
			(hide yes)
			(effects
				(font
					(size 1.27 0.9652)
					(thickness 0.000001)
				)
				(justify left mirror)
			)
		)
		(property "Device Type" "REST4024"
			(at 0.148158 1.3462 270)
			(unlocked yes)
			(layer "B.Fab")
			(hide yes)
			(effects
				(font
					(size 1.27 0.9652)
					(thickness 0.000001)
				)
				(justify left mirror)
			)
		)
		(duplicate_pad_numbers_are_jumpers no)
		(fp_poly
			(pts
				(xy -0.635 1.0668) (xy -0.635 -1.0668) (xy 0.635 -1.0668) (xy 0.635 1.0668)
			)
			(stroke
				(width 0)
				(type default)
			)
			(fill no)
			(layer "B.CrtYd")
		)
		(fp_line
			(start -0.254 -0.508)
			(end -0.254 0.508)
			(stroke
				(width 0.0254)
				(type default)
			)
			(layer "B.Fab")
		)
		(fp_line
			(start -0.254 0.508)
			(end 0.254 0.508)
			(stroke
				(width 0.0254)
				(type default)
			)
			(layer "B.Fab")
		)
		(fp_line
			(start 0.254 -0.508)
			(end -0.254 -0.508)
			(stroke
				(width 0.0254)
				(type default)
			)
			(layer "B.Fab")
		)
		(fp_line
			(start 0.254 0.508)
			(end 0.254 -0.508)
			(stroke
				(width 0.0254)
				(type default)
			)
			(layer "B.Fab")
		)
		(pad "1" smd rect
			(at 0 -0.4191 180)
			(size 0.508 0.5334)
			(layers "B.Cu" "B.Mask" "B.Paste")
			(net "VDD_3.3V")
		)
		(pad "2" smd rect
			(at 0 0.4191 180)
			(size 0.508 0.5334)
			(layers "B.Cu" "B.Mask" "B.Paste")
			(net "NFP_CFG_SPI_FLASH_MISO")
		)
		(zone
			(layer "B.Cu")
			(hatch none 0.5)
			(connect_pads
				(clearance 0)
			)
			(min_thickness 0.25)
			(keepout
				(tracks not_allowed)
				(vias allowed)
				(pads allowed)
				(copperpour not_allowed)
				(footprints allowed)
			)
			(placement
				(enabled no)
				(sheetname "")
			)
			(fill
				(thermal_gap 0.5)
				(thermal_bridge_width 0.5)
				(island_removal_mode 0)
			)
			(polygon
				(pts
					(xy 22.3266 13.5636) (xy 22.3266 13.6144) (xy 22.3774 13.6144) (xy 22.3774 13.5636)
				)
			)
		)
	)
	(footprint ""
		(layer "B.Cu")
		(at 72.251011 17.455998)
		(property "Reference" "V_A-DQ26"
			(at 0 0 0)
			(layer "B.SilkS")
			(hide yes)
			(effects
				(font
					(size 1.27 1.27)
				)
				(justify mirror)
			)
		)
		(property "Value" ""
			(at 0 0 0)
			(layer "B.Fab")
			(effects
				(font
					(size 1.27 1.27)
				)
				(justify mirror)
			)
		)
		(duplicate_pad_numbers_are_jumpers no)
		(pad "1" thru_hole circle
			(at 0 0 180)
			(size 0.4572 0.4572)
			(drill 0.20574)
			(layers "*.Cu" "*.Mask")
			(remove_unused_layers no)
			(net "DDR0_32A_DQ26")
			(clearance 0.1143)
			(thermal_gap 0.1143)
		)
	)
	(footprint ""
		(layer "B.Cu")
		(at 74.651006 29.812996)
		(property "Reference" "V_A-DM4"
			(at 0 0 0)
			(layer "B.SilkS")
			(hide yes)
			(effects
				(font
					(size 1.27 1.27)
				)
				(justify mirror)
			)
		)
		(property "Value" ""
			(at 0 0 0)
			(layer "B.Fab")
			(effects
				(font
					(size 1.27 1.27)
				)
				(justify mirror)
			)
		)
		(duplicate_pad_numbers_are_jumpers no)
		(pad "1" thru_hole circle
			(at 0 0 180)
			(size 0.4572 0.4572)
			(drill 0.20574)
			(layers "*.Cu" "*.Mask")
			(remove_unused_layers no)
			(net "DDR0_32A_DM4")
			(clearance 0.1143)
			(thermal_gap 0.1143)
		)
	)
	(footprint ""
		(layer "B.Cu")
		(at 80.01 41.5036 180)
		(property "Reference" "C165"
			(at -0.635 1.34493 0)
			(unlocked yes)
			(layer "B.SilkS")
			(effects
				(font
					(size 0.7874 0.5842)
					(thickness 0.127)
				)
				(justify left mirror)
			)
		)
		(property "Value" "0.22UF"
			(at 0.091846 0.2921 90)
			(unlocked yes)
			(layer "B.Fab")
			(hide yes)
			(effects
				(font
					(size 0.7874 0.5842)
					(thickness 0.2032)
				)
				(justify left mirror)
			)
		)
		(property "Device Type" "CAPC0062"
			(at 0.091846 0.2921 90)
			(unlocked yes)
			(layer "B.Fab")
			(hide yes)
			(effects
				(font
					(size 0.7874 0.5842)
					(thickness 0.2032)
				)
				(justify left mirror)
			)
		)
		(duplicate_pad_numbers_are_jumpers no)
		(fp_poly
			(pts
				(xy -0.635 1.0668) (xy -0.635 -1.0668) (xy 0.635 -1.0668) (xy 0.635 1.0668)
			)
			(stroke
				(width 0)
				(type default)
			)
			(fill no)
			(layer "B.CrtYd")
		)
		(fp_line
			(start 0.254 0.508)
			(end 0.254 -0.508)
			(stroke
				(width 0.0254)
				(type default)
			)
			(layer "B.Fab")
		)
		(fp_line
			(start 0.254 -0.508)
			(end -0.254 -0.508)
			(stroke
				(width 0.0254)
				(type default)
			)
			(layer "B.Fab")
		)
		(fp_line
			(start -0.254 0.508)
			(end 0.254 0.508)
			(stroke
				(width 0.0254)
				(type default)
			)
			(layer "B.Fab")
		)
		(fp_line
			(start -0.254 -0.508)
			(end -0.254 0.508)
			(stroke
				(width 0.0254)
				(type default)
			)
			(layer "B.Fab")
		)
		(pad "1" smd rect
			(at 0 -0.4191)
			(size 0.508 0.5334)
			(layers "B.Cu" "B.Mask" "B.Paste")
			(net "11N2202")
		)
		(pad "2" smd rect
			(at 0 0.4191)
			(size 0.508 0.5334)
			(layers "B.Cu" "B.Mask" "B.Paste")
			(net "GND")
		)
		(zone
			(layer "B.Cu")
			(hatch none 0.5)
			(connect_pads
				(clearance 0)
			)
			(min_thickness 0.25)
			(keepout
				(tracks not_allowed)
				(vias allowed)
				(pads allowed)
				(copperpour not_allowed)
				(footprints allowed)
			)
			(placement
				(enabled no)
				(sheetname "")
			)
			(fill
				(thermal_gap 0.5)
				(thermal_bridge_width 0.5)
				(island_removal_mode 0)
			)
			(polygon
				(pts
					(xy 80.0354 41.529) (xy 80.0354 41.4782) (xy 79.9846 41.4782) (xy 79.9846 41.529)
				)
			)
		)
	)
	(footprint ""
		(layer "B.Cu")
		(at 40.737028 23.041991 90)
		(property "Reference" "C86"
			(at 1.425321 -0.605028 0)
			(unlocked yes)
			(layer "B.SilkS")
			(effects
				(font
					(size 0.7874 0.5842)
					(thickness 0.127)
				)
				(justify mirror)
			)
		)
		(property "Value" ""
			(at 0 0 90)
			(layer "B.Fab")
			(effects
				(font
					(size 1.27 1.27)
				)
				(justify mirror)
			)
		)
		(duplicate_pad_numbers_are_jumpers no)
		(fp_circle
			(center 0 0)
			(end 0 0.104648)
			(stroke
				(width 0.1016)
				(type default)
			)
			(fill no)
			(layer "B.SilkS")
		)
		(fp_poly
			(pts
				(xy 0.381 -0.889) (xy 0.381 0.889) (xy -0.381 0.889) (xy -0.381 -0.889)
			)
			(stroke
				(width 0)
				(type default)
			)
			(fill no)
			(layer "B.CrtYd")
		)
		(fp_line
			(start 0.508 -1.016)
			(end 0.254 -1.016)
			(stroke
				(width 0.0254)
				(type default)
			)
			(layer "B.Fab")
		)
		(fp_line
			(start 0.254 -1.016)
			(end -0.508 -1.016)
			(stroke
				(width 0.0254)
				(type default)
			)
			(layer "B.Fab")
		)
		(fp_line
			(start -0.508 -1.016)
			(end -0.508 1.016)
			(stroke
				(width 0.0254)
				(type default)
			)
			(layer "B.Fab")
		)
		(fp_line
			(start 0.508 1.016)
			(end 0.508 -1.016)
			(stroke
				(width 0.0254)
				(type default)
			)
			(layer "B.Fab")
		)
		(fp_line
			(start -0.508 1.016)
			(end 0.508 1.016)
			(stroke
				(width 0.0254)
				(type default)
			)
			(layer "B.Fab")
		)
		(pad "1" smd custom
			(at 0 -0.500126 270)
			(size 0.127 0.127)
			(layers "B.Cu" "B.Mask" "B.Paste")
			(net "VDDA_TS0")
			(options
				(clearance outline)
				(anchor circle)
			)
			(primitives
				(gr_poly
					(pts
						(xy -0.1778 0.254) (xy 0.1778 0.254) (xy 0.254 0.1778) (xy 0.254 -0.1778) (xy 0.1778 -0.254) (xy -0.1778 -0.254)
						(xy -0.254 -0.1778) (xy -0.254 0.1778)
					)
					(width 0)
					(fill yes)
				)
			)
		)
		(pad "2" smd custom
			(at 0 0.500126 270)
			(size 0.127 0.127)
			(layers "B.Cu" "B.Mask" "B.Paste")
			(net "GND")
			(options
				(clearance outline)
				(anchor circle)
			)
			(primitives
				(gr_poly
					(pts
						(xy -0.1778 0.254) (xy 0.1778 0.254) (xy 0.254 0.1778) (xy 0.254 -0.1778) (xy 0.1778 -0.254) (xy -0.1778 -0.254)
						(xy -0.254 -0.1778) (xy -0.254 0.1778)
					)
					(width 0)
					(fill yes)
				)
			)
		)
	)
	(footprint ""
		(layer "B.Cu")
		(at 1.2319 16.129 90)
		(property "Reference" "R386"
			(at -0.28067 -1.1049 0)
			(unlocked yes)
			(layer "B.SilkS")
			(effects
				(font
					(size 0.7874 0.5842)
					(thickness 0.127)
				)
				(justify left mirror)
			)
		)
		(property "Value" "0"
			(at 0.148158 1.3462 0)
			(unlocked yes)
			(layer "B.Fab")
			(hide yes)
			(effects
				(font
					(size 1.27 0.9652)
					(thickness 0.000001)
				)
				(justify left mirror)
			)
		)
		(property "Device Type" "REST1111"
			(at 0.148158 1.3462 0)
			(unlocked yes)
			(layer "B.Fab")
			(hide yes)
			(effects
				(font
					(size 1.27 0.9652)
					(thickness 0.000001)
				)
				(justify left mirror)
			)
		)
		(duplicate_pad_numbers_are_jumpers no)
		(fp_poly
			(pts
				(xy -0.635 1.0668) (xy -0.635 -1.0668) (xy 0.635 -1.0668) (xy 0.635 1.0668)
			)
			(stroke
				(width 0)
				(type default)
			)
			(fill no)
			(layer "B.CrtYd")
		)
		(fp_line
			(start 0.254 -0.508)
			(end -0.254 -0.508)
			(stroke
				(width 0.0254)
				(type default)
			)
			(layer "B.Fab")
		)
		(fp_line
			(start -0.254 -0.508)
			(end -0.254 0.508)
			(stroke
				(width 0.0254)
				(type default)
			)
			(layer "B.Fab")
		)
		(fp_line
			(start 0.254 0.508)
			(end 0.254 -0.508)
			(stroke
				(width 0.0254)
				(type default)
			)
			(layer "B.Fab")
		)
		(fp_line
			(start -0.254 0.508)
			(end 0.254 0.508)
			(stroke
				(width 0.0254)
				(type default)
			)
			(layer "B.Fab")
		)
		(pad "1" smd rect
			(at 0 -0.4191 270)
			(size 0.508 0.5334)
			(layers "B.Cu" "B.Mask" "B.Paste")
			(net "NWK0_I2C_SDA")
		)
		(pad "2" smd rect
			(at 0 0.4191 270)
			(size 0.508 0.5334)
			(layers "B.Cu" "B.Mask" "B.Paste")
			(net "MUX_NFP_GPIO1_NWK0_I2C_SDA")
		)
		(zone
			(layer "B.Cu")
			(hatch none 0.5)
			(connect_pads
				(clearance 0)
			)
			(min_thickness 0.25)
			(keepout
				(tracks not_allowed)
				(vias allowed)
				(pads allowed)
				(copperpour not_allowed)
				(footprints allowed)
			)
			(placement
				(enabled no)
				(sheetname "")
			)
			(fill
				(thermal_gap 0.5)
				(thermal_bridge_width 0.5)
				(island_removal_mode 0)
			)
			(polygon
				(pts
					(xy 1.2065 16.1544) (xy 1.2573 16.1544) (xy 1.2573 16.1036) (xy 1.2065 16.1036)
				)
			)
		)
	)
	(footprint ""
		(layer "B.Cu")
		(at 58.389012 0.762 180)
		(property "Reference" "C158"
			(at 0.145212 0.8763 270)
			(unlocked yes)
			(layer "B.SilkS")
			(effects
				(font
					(size 0.7874 0.5842)
					(thickness 0.127)
				)
				(justify left mirror)
			)
		)
		(property "Value" "0.22UF"
			(at 0.091846 0.2921 90)
			(unlocked yes)
			(layer "B.Fab")
			(hide yes)
			(effects
				(font
					(size 0.7874 0.5842)
					(thickness 0.2032)
				)
				(justify left mirror)
			)
		)
		(property "Device Type" "CAPC0062"
			(at 0.091846 0.2921 90)
			(unlocked yes)
			(layer "B.Fab")
			(hide yes)
			(effects
				(font
					(size 0.7874 0.5842)
					(thickness 0.2032)
				)
				(justify left mirror)
			)
		)
		(duplicate_pad_numbers_are_jumpers no)
		(fp_poly
			(pts
				(xy -0.635 1.0668) (xy -0.635 -1.0668) (xy 0.635 -1.0668) (xy 0.635 1.0668)
			)
			(stroke
				(width 0)
				(type default)
			)
			(fill no)
			(layer "B.CrtYd")
		)
		(fp_line
			(start 0.254 0.508)
			(end 0.254 -0.508)
			(stroke
				(width 0.0254)
				(type default)
			)
			(layer "B.Fab")
		)
		(fp_line
			(start 0.254 -0.508)
			(end -0.254 -0.508)
			(stroke
				(width 0.0254)
				(type default)
			)
			(layer "B.Fab")
		)
		(fp_line
			(start -0.254 0.508)
			(end 0.254 0.508)
			(stroke
				(width 0.0254)
				(type default)
			)
			(layer "B.Fab")
		)
		(fp_line
			(start -0.254 -0.508)
			(end -0.254 0.508)
			(stroke
				(width 0.0254)
				(type default)
			)
			(layer "B.Fab")
		)
		(pad "1" smd rect
			(at 0 -0.4191)
			(size 0.508 0.5334)
			(layers "B.Cu" "B.Mask" "B.Paste")
			(net "_NFP_PCIE0_PER2_N")
		)
		(pad "2" smd rect
			(at 0 0.4191)
			(size 0.508 0.5334)
			(layers "B.Cu" "B.Mask" "B.Paste")
			(net "NFP_PCIE0_PER2_N")
		)
		(zone
			(layer "B.Cu")
			(hatch none 0.5)
			(connect_pads
				(clearance 0)
			)
			(min_thickness 0.25)
			(keepout
				(tracks not_allowed)
				(vias allowed)
				(pads allowed)
				(copperpour not_allowed)
				(footprints allowed)
			)
			(placement
				(enabled no)
				(sheetname "")
			)
			(fill
				(thermal_gap 0.5)
				(thermal_bridge_width 0.5)
				(island_removal_mode 0)
			)
			(polygon
				(pts
					(xy 58.414412 0.7874) (xy 58.414412 0.7366) (xy 58.363612 0.7366) (xy 58.363612 0.7874)
				)
			)
		)
	)
	(footprint ""
		(layer "B.Cu")
		(at 26.289 10.414 90)
		(property "Reference" "R148"
			(at 0 0 90)
			(layer "B.SilkS")
			(hide yes)
			(effects
				(font
					(size 1.27 1.27)
				)
				(justify mirror)
			)
		)
		(property "Value" "0"
			(at 0.148158 1.3462 0)
			(unlocked yes)
			(layer "B.Fab")
			(hide yes)
			(effects
				(font
					(size 1.27 0.9652)
					(thickness 0.000001)
				)
				(justify left mirror)
			)
		)
		(property "Device Type" "REST1111"
			(at 0.148158 1.3462 0)
			(unlocked yes)
			(layer "B.Fab")
			(hide yes)
			(effects
				(font
					(size 1.27 0.9652)
					(thickness 0.000001)
				)
				(justify left mirror)
			)
		)
		(duplicate_pad_numbers_are_jumpers no)
		(fp_poly
			(pts
				(xy -0.635 1.0668) (xy -0.635 -1.0668) (xy 0.635 -1.0668) (xy 0.635 1.0668)
			)
			(stroke
				(width 0)
				(type default)
			)
			(fill no)
			(layer "B.CrtYd")
		)
		(fp_line
			(start 0.254 -0.508)
			(end -0.254 -0.508)
			(stroke
				(width 0.0254)
				(type default)
			)
			(layer "B.Fab")
		)
		(fp_line
			(start -0.254 -0.508)
			(end -0.254 0.508)
			(stroke
				(width 0.0254)
				(type default)
			)
			(layer "B.Fab")
		)
		(fp_line
			(start 0.254 0.508)
			(end 0.254 -0.508)
			(stroke
				(width 0.0254)
				(type default)
			)
			(layer "B.Fab")
		)
		(fp_line
			(start -0.254 0.508)
			(end 0.254 0.508)
			(stroke
				(width 0.0254)
				(type default)
			)
			(layer "B.Fab")
		)
		(pad "1" smd rect
			(at 0 -0.4191 270)
			(size 0.508 0.5334)
			(layers "B.Cu" "B.Mask" "B.Paste")
			(net "PGRM_JTAG_TDI")
		)
		(pad "2" smd rect
			(at 0 0.4191 270)
			(size 0.508 0.5334)
			(layers "B.Cu" "B.Mask" "B.Paste")
			(net "PGRM_JTAG_TDO")
		)
		(zone
			(layer "B.Cu")
			(hatch none 0.5)
			(connect_pads
				(clearance 0)
			)
			(min_thickness 0.25)
			(keepout
				(tracks not_allowed)
				(vias allowed)
				(pads allowed)
				(copperpour not_allowed)
				(footprints allowed)
			)
			(placement
				(enabled no)
				(sheetname "")
			)
			(fill
				(thermal_gap 0.5)
				(thermal_bridge_width 0.5)
				(island_removal_mode 0)
			)
			(polygon
				(pts
					(xy 26.2636 10.4394) (xy 26.3144 10.4394) (xy 26.3144 10.3886) (xy 26.2636 10.3886)
				)
			)
		)
	)
	(footprint ""
		(layer "B.Cu")
		(at 30.734 22.225 180)
		(property "Reference" "R55"
			(at 0 0 0)
			(layer "B.SilkS")
			(hide yes)
			(effects
				(font
					(size 1.27 1.27)
				)
				(justify mirror)
			)
		)
		(property "Value" "4.75K"
			(at 0.148158 1.3462 90)
			(unlocked yes)
			(layer "B.Fab")
			(hide yes)
			(effects
				(font
					(size 1.27 0.9652)
					(thickness 0.000001)
				)
				(justify left mirror)
			)
		)
		(property "Device Type" "REST4024"
			(at 0.148158 1.3462 90)
			(unlocked yes)
			(layer "B.Fab")
			(hide yes)
			(effects
				(font
					(size 1.27 0.9652)
					(thickness 0.000001)
				)
				(justify left mirror)
			)
		)
		(duplicate_pad_numbers_are_jumpers no)
		(fp_poly
			(pts
				(xy -0.635 1.0668) (xy -0.635 -1.0668) (xy 0.635 -1.0668) (xy 0.635 1.0668)
			)
			(stroke
				(width 0)
				(type default)
			)
			(fill no)
			(layer "B.CrtYd")
		)
		(fp_line
			(start 0.254 0.508)
			(end 0.254 -0.508)
			(stroke
				(width 0.0254)
				(type default)
			)
			(layer "B.Fab")
		)
		(fp_line
			(start 0.254 -0.508)
			(end -0.254 -0.508)
			(stroke
				(width 0.0254)
				(type default)
			)
			(layer "B.Fab")
		)
		(fp_line
			(start -0.254 0.508)
			(end 0.254 0.508)
			(stroke
				(width 0.0254)
				(type default)
			)
			(layer "B.Fab")
		)
		(fp_line
			(start -0.254 -0.508)
			(end -0.254 0.508)
			(stroke
				(width 0.0254)
				(type default)
			)
			(layer "B.Fab")
		)
		(pad "1" smd rect
			(at 0 -0.4191)
			(size 0.508 0.5334)
			(layers "B.Cu" "B.Mask" "B.Paste")
			(net "CPLD_VERSION_1")
		)
		(pad "2" smd rect
			(at 0 0.4191)
			(size 0.508 0.5334)
			(layers "B.Cu" "B.Mask" "B.Paste")
			(net "GND")
		)
		(zone
			(layer "B.Cu")
			(hatch none 0.5)
			(connect_pads
				(clearance 0)
			)
			(min_thickness 0.25)
			(keepout
				(tracks not_allowed)
				(vias allowed)
				(pads allowed)
				(copperpour not_allowed)
				(footprints allowed)
			)
			(placement
				(enabled no)
				(sheetname "")
			)
			(fill
				(thermal_gap 0.5)
				(thermal_bridge_width 0.5)
				(island_removal_mode 0)
			)
			(polygon
				(pts
					(xy 30.7594 22.2504) (xy 30.7594 22.1996) (xy 30.7086 22.1996) (xy 30.7086 22.2504)
				)
			)
		)
	)
	(footprint ""
		(layer "B.Cu")
		(at 83.450989 13.456006)
		(property "Reference" "V2_A-A07"
			(at 0 0 0)
			(layer "B.SilkS")
			(hide yes)
			(effects
				(font
					(size 1.27 1.27)
				)
				(justify mirror)
			)
		)
		(property "Value" ""
			(at 0 0 0)
			(layer "B.Fab")
			(effects
				(font
					(size 1.27 1.27)
				)
				(justify mirror)
			)
		)
		(duplicate_pad_numbers_are_jumpers no)
		(pad "1" thru_hole circle
			(at 0 0 180)
			(size 0.4572 0.4572)
			(drill 0.20574)
			(layers "*.Cu" "*.Mask")
			(remove_unused_layers no)
			(net "DDR0_32A_A7")
			(clearance 0.1143)
			(thermal_gap 0.1143)
		)
	)
)
